(kicad_pcb
	(version 20241229)
	(generator "pcbnew")
	(generator_version "9.0")
	(general
		(thickness 1.62)
		(legacy_teardrops no)
	)
	(paper "A3")
	(title_block
		(title "COM Express 7 Baseboard")
		(date "2025-02-04")
		(rev "1.1.2")
		(company "Antmicro Ltd")
		(comment 1 "www.antmicro.com")
		(comment 9 "footprints 306-310 of 802")
	)
	(layers
		(0 "F.Cu" signal)
		(4 "In1.Cu" signal)
		(6 "In2.Cu" signal)
		(8 "In3.Cu" signal)
		(10 "In4.Cu" signal)
		(12 "In5.Cu" signal)
		(14 "In6.Cu" signal)
		(2 "B.Cu" signal)
		(9 "F.Adhes" user "F.Adhesive")
		(11 "B.Adhes" user "B.Adhesive")
		(13 "F.Paste" user)
		(15 "B.Paste" user)
		(5 "F.SilkS" user "F.Silkscreen")
		(7 "B.SilkS" user "B.Silkscreen")
		(1 "F.Mask" user)
		(3 "B.Mask" user)
		(17 "Dwgs.User" user "User.Drawings")
		(19 "Cmts.User" user "User.Comments")
		(21 "Eco1.User" user "User.Eco1")
		(23 "Eco2.User" user "User.Eco2")
		(25 "Edge.Cuts" user)
		(27 "Margin" user)
		(31 "F.CrtYd" user "F.Courtyard")
		(29 "B.CrtYd" user "B.Courtyard")
		(35 "F.Fab" user)
		(33 "B.Fab" user)
	)
	(footprint "antmicro-footprints:R_0402_1005Metric"
		(layer "F.Cu")
		(at 242.8 132.36 -90)
		(descr "Resistor SMD 0402")
		(tags "resistor SMD 0402")
		(property "Reference" "R176"
			(at 0.85 -0.45 90)
			(layer "F.SilkS")
			(effects
				(font
					(size 0.7 0.7)
					(thickness 0.15)
				)
				(justify right bottom)
			)
		)
		(property "Value" "R_10k_0402"
			(at -1.011843 1.772047 90)
			(layer "F.Fab")
			(effects
				(font
					(size 0.7 0.7)
					(thickness 0.15)
				)
				(justify right bottom)
			)
		)
		(property "Datasheet" "https://www.bourns.com/docs/product-datasheets/cr.pdf"
			(at 0 0 270)
			(layer "F.Fab")
			(hide yes)
			(effects
				(font
					(size 1.27 1.27)
					(thickness 0.15)
				)
			)
		)
		(property "Author" "Antmicro"
			(at 110.44 375.16 0)
			(layer "F.Fab")
			(hide yes)
			(effects
				(font
					(size 1 1)
					(thickness 0.15)
				)
			)
		)
		(property "License" "Apache-2.0"
			(at 110.44 375.16 0)
			(layer "F.Fab")
			(hide yes)
			(effects
				(font
					(size 1 1)
					(thickness 0.15)
				)
			)
		)
		(property "MPN" "CR0402-FX-1002GLF"
			(at 110.44 375.16 0)
			(layer "F.Fab")
			(hide yes)
			(effects
				(font
					(size 1 1)
					(thickness 0.15)
				)
			)
		)
		(property "Manufacturer" "Bourns"
			(at 110.44 375.16 0)
			(layer "F.Fab")
			(hide yes)
			(effects
				(font
					(size 1 1)
					(thickness 0.15)
				)
			)
		)
		(property "Public" "False"
			(at 110.44 375.16 0)
			(layer "F.Fab")
			(hide yes)
			(effects
				(font
					(size 1 1)
					(thickness 0.15)
				)
			)
		)
		(property "Tolerance" "1%"
			(at 110.44 375.16 0)
			(layer "F.Fab")
			(hide yes)
			(effects
				(font
					(size 1 1)
					(thickness 0.15)
				)
			)
		)
		(property "Val" "10k"
			(at 110.44 375.16 0)
			(layer "F.Fab")
			(hide yes)
			(effects
				(font
					(size 1 1)
					(thickness 0.15)
				)
			)
		)
		(sheetname "Com Express 7 MGMT")
		(sheetfile "com_express_7_mgmt.kicad_sch")
		(attr smd)
		(fp_rect
			(start -0.925 -0.47)
			(end 0.925 0.47)
			(stroke
				(width 0.05)
				(type default)
			)
			(fill no)
			(layer "F.CrtYd")
		)
		(fp_rect
			(start -0.5 -0.25)
			(end 0.5 0.25)
			(stroke
				(width 0.15)
				(type solid)
			)
			(fill no)
			(layer "F.Fab")
		)
		(pad "1" smd roundrect
			(at -0.48 0 270)
			(size 0.59 0.64)
			(layers "F.Cu" "F.Mask" "F.Paste")
			(roundrect_rratio 0.25)
			(net 873 "Net-(U34-EN)")
			(pintype "passive")
			(teardrops
				(best_length_ratio 0.2)
				(max_length 1)
				(best_width_ratio 0.9)
				(max_width 2)
				(curved_edges yes)
				(filter_ratio 0.9)
				(enabled yes)
				(allow_two_segments yes)
				(prefer_zone_connections yes)
			)
		)
		(pad "2" smd roundrect
			(at 0.48 0 270)
			(size 0.59 0.64)
			(layers "F.Cu" "F.Mask" "F.Paste")
			(roundrect_rratio 0.25)
			(net 73 "+3V3_AON")
			(pintype "passive")
			(teardrops
				(best_length_ratio 0.2)
				(max_length 1)
				(best_width_ratio 0.9)
				(max_width 2)
				(curved_edges yes)
				(filter_ratio 0.9)
				(enabled yes)
				(allow_two_segments yes)
				(prefer_zone_connections yes)
			)
		)
	)
	(footprint "antmicro-footprints:C_0201"
		(layer "F.Cu")
		(at 137.412 147.31 90)
		(descr "Capacitor SMD 0201")
		(tags "capacitor SMD 0201")
		(property "Reference" "C180"
			(at -4.099 0.288 90)
			(layer "F.SilkS")
			(effects
				(font
					(size 0.7 0.7)
					(thickness 0.15)
				)
				(justify left bottom)
			)
		)
		(property "Value" "C_100n_0201_25V"
			(at 0 1.4 90)
			(layer "F.Fab")
			(effects
				(font
					(size 0.7 0.7)
					(thickness 0.15)
				)
				(justify left bottom)
			)
		)
		(property "Datasheet" "https://product.tdk.com/en/search/capacitor/ceramic/mlcc/info?part_no=C0603X5R1E104K030BB"
			(at 0 0 90)
			(layer "F.Fab")
			(hide yes)
			(effects
				(font
					(size 1.27 1.27)
					(thickness 0.15)
				)
			)
		)
		(property "Author" "Antmicro"
			(at 284.722 9.898 0)
			(layer "F.Fab")
			(hide yes)
			(effects
				(font
					(size 1 1)
					(thickness 0.15)
				)
			)
		)
		(property "Dielectric" ""
			(at 284.722 9.898 0)
			(layer "F.Fab")
			(hide yes)
			(effects
				(font
					(size 1 1)
					(thickness 0.15)
				)
			)
		)
		(property "License" "Apache-2.0"
			(at 284.722 9.898 0)
			(layer "F.Fab")
			(hide yes)
			(effects
				(font
					(size 1 1)
					(thickness 0.15)
				)
			)
		)
		(property "MPN" "C0603X5R1E104K030BB"
			(at 284.722 9.898 0)
			(layer "F.Fab")
			(hide yes)
			(effects
				(font
					(size 1 1)
					(thickness 0.15)
				)
			)
		)
		(property "Manufacturer" "TDK"
			(at 284.722 9.898 0)
			(layer "F.Fab")
			(hide yes)
			(effects
				(font
					(size 1 1)
					(thickness 0.15)
				)
			)
		)
		(property "Public" "False"
			(at 284.722 9.898 0)
			(layer "F.Fab")
			(hide yes)
			(effects
				(font
					(size 1 1)
					(thickness 0.15)
				)
			)
		)
		(property "Val" "100n"
			(at 284.722 9.898 0)
			(layer "F.Fab")
			(hide yes)
			(effects
				(font
					(size 1 1)
					(thickness 0.15)
				)
			)
		)
		(property "Voltage" "25V"
			(at 284.722 9.898 0)
			(layer "F.Fab")
			(hide yes)
			(effects
				(font
					(size 1 1)
					(thickness 0.15)
				)
			)
		)
		(sheetname "KR to SFI #2")
		(sheetfile "kr_sfi.kicad_sch")
		(attr smd)
		(fp_rect
			(start -0.7 -0.35)
			(end 0.7 0.35)
			(stroke
				(width 0.05)
				(type default)
			)
			(fill no)
			(layer "F.CrtYd")
		)
		(fp_rect
			(start 0.3 0.15)
			(end -0.301 -0.149)
			(stroke
				(width 0.15)
				(type solid)
			)
			(fill no)
			(layer "F.Fab")
		)
		(pad "" smd roundrect
			(at -0.349 -0.002 90)
			(size 0.318 0.36)
			(layers "F.Paste")
			(roundrect_rratio 0.25)
			(teardrops
				(best_length_ratio 0.2)
				(max_length 1)
				(best_width_ratio 0.9)
				(max_width 2)
				(curved_edges yes)
				(filter_ratio 0.9)
				(enabled yes)
				(allow_two_segments yes)
				(prefer_zone_connections yes)
			)
		)
		(pad "" smd roundrect
			(at 0.341 -0.002 90)
			(size 0.318 0.36)
			(layers "F.Paste")
			(roundrect_rratio 0.25)
			(teardrops
				(best_length_ratio 0.2)
				(max_length 1)
				(best_width_ratio 0.9)
				(max_width 2)
				(curved_edges yes)
				(filter_ratio 0.9)
				(enabled yes)
				(allow_two_segments yes)
				(prefer_zone_connections yes)
			)
		)
		(pad "1" smd roundrect
			(at -0.321 -0.002 90)
			(size 0.46 0.4)
			(layers "F.Cu" "F.Mask")
			(roundrect_rratio 0.25)
			(net 119 "/2xSFP+/10GKR_SFP1.TX+")
			(pintype "passive")
			(teardrops
				(best_length_ratio 0.2)
				(max_length 1)
				(best_width_ratio 0.9)
				(max_width 2)
				(curved_edges yes)
				(filter_ratio 0.9)
				(enabled yes)
				(allow_two_segments yes)
				(prefer_zone_connections yes)
			)
		)
		(pad "2" smd roundrect
			(at 0.32 -0.002 90)
			(size 0.46 0.4)
			(layers "F.Cu" "F.Mask")
			(roundrect_rratio 0.25)
			(net 120 "/2xSFP+/KR to SFI #2/KR_C.TX+")
			(pintype "passive")
			(teardrops
				(best_length_ratio 0.2)
				(max_length 1)
				(best_width_ratio 0.9)
				(max_width 2)
				(curved_edges yes)
				(filter_ratio 0.9)
				(enabled yes)
				(allow_two_segments yes)
				(prefer_zone_connections yes)
			)
		)
	)
	(footprint "antmicro-footprints:R_0402_1005Metric"
		(layer "F.Cu")
		(at 131.25 97.91)
		(descr "Resistor SMD 0402")
		(tags "resistor SMD 0402")
		(property "Reference" "R30"
			(at -1.05 -0.55 0)
			(layer "F.SilkS")
			(effects
				(font
					(size 0.7 0.7)
					(thickness 0.15)
				)
				(justify left bottom)
			)
		)
		(property "Value" "R_0R_0402"
			(at -1.011843 1.772047 0)
			(layer "F.Fab")
			(effects
				(font
					(size 0.7 0.7)
					(thickness 0.15)
				)
				(justify left bottom)
			)
		)
		(property "Datasheet" "https://industrial.panasonic.com/cdbs/www-data/pdf/RDA0000/AOA0000C301.pdf"
			(at 0 0 0)
			(layer "F.Fab")
			(hide yes)
			(effects
				(font
					(size 1.27 1.27)
					(thickness 0.15)
				)
			)
		)
		(property "Author" "Antmicro"
			(at 0 0 0)
			(layer "F.Fab")
			(hide yes)
			(effects
				(font
					(size 1 1)
					(thickness 0.15)
				)
			)
		)
		(property "Current" "1A"
			(at 0 0 0)
			(layer "F.Fab")
			(hide yes)
			(effects
				(font
					(size 1 1)
					(thickness 0.15)
				)
			)
		)
		(property "License" "Apache-2.0"
			(at 0 0 0)
			(layer "F.Fab")
			(hide yes)
			(effects
				(font
					(size 1 1)
					(thickness 0.15)
				)
			)
		)
		(property "MPN" "ERJ2GE0R00X"
			(at 0 0 0)
			(layer "F.Fab")
			(hide yes)
			(effects
				(font
					(size 1 1)
					(thickness 0.15)
				)
			)
		)
		(property "Manufacturer" "Panasonic"
			(at 0 0 0)
			(layer "F.Fab")
			(hide yes)
			(effects
				(font
					(size 1 1)
					(thickness 0.15)
				)
			)
		)
		(property "Public" "False"
			(at 0 0 0)
			(layer "F.Fab")
			(hide yes)
			(effects
				(font
					(size 1 1)
					(thickness 0.15)
				)
			)
		)
		(property "Tolerance" ""
			(at 0 0 0)
			(layer "F.Fab")
			(hide yes)
			(effects
				(font
					(size 1 1)
					(thickness 0.15)
				)
			)
		)
		(property "Val" "0R"
			(at 0 0 0)
			(layer "F.Fab")
			(hide yes)
			(effects
				(font
					(size 1 1)
					(thickness 0.15)
				)
			)
		)
		(sheetname "2xUSB3.0+RJ45")
		(sheetfile "usb3+rj45.kicad_sch")
		(attr smd)
		(fp_rect
			(start -0.925 -0.47)
			(end 0.925 0.47)
			(stroke
				(width 0.05)
				(type default)
			)
			(fill no)
			(layer "F.CrtYd")
		)
		(fp_rect
			(start -0.5 -0.25)
			(end 0.5 0.25)
			(stroke
				(width 0.15)
				(type solid)
			)
			(fill no)
			(layer "F.Fab")
		)
		(pad "1" smd roundrect
			(at -0.48 0)
			(size 0.59 0.64)
			(layers "F.Cu" "F.Mask" "F.Paste")
			(roundrect_rratio 0.25)
			(net 51 "Net-(C13-Pad1)")
			(pintype "passive")
			(teardrops
				(best_length_ratio 0.2)
				(max_length 1)
				(best_width_ratio 0.9)
				(max_width 2)
				(curved_edges yes)
				(filter_ratio 0.9)
				(enabled yes)
				(allow_two_segments yes)
				(prefer_zone_connections yes)
			)
		)
		(pad "2" smd roundrect
			(at 0.48 0)
			(size 0.59 0.64)
			(layers "F.Cu" "F.Mask" "F.Paste")
			(roundrect_rratio 0.25)
			(net 296 "/2xUSB3.0+RJ45/GbE.CTREF")
			(pintype "passive")
			(teardrops
				(best_length_ratio 0.2)
				(max_length 1)
				(best_width_ratio 0.9)
				(max_width 2)
				(curved_edges yes)
				(filter_ratio 0.9)
				(enabled yes)
				(allow_two_segments yes)
				(prefer_zone_connections yes)
			)
		)
	)
	(footprint "antmicro-footprints:C_0402_1005Metric"
		(layer "F.Cu")
		(at 253.32825 127.651748 90)
		(descr "Capacitor SMD 0402")
		(tags "capacitor SMD 0402")
		(property "Reference" "C97"
			(at 0.841748 0.47175 90)
			(layer "F.SilkS")
			(effects
				(font
					(size 0.7 0.7)
					(thickness 0.15)
				)
				(justify left bottom)
			)
		)
		(property "Value" "C_100n_0402"
			(at -1.022927 2.155213 90)
			(layer "F.Fab")
			(effects
				(font
					(size 0.7 0.7)
					(thickness 0.15)
				)
				(justify left bottom)
			)
		)
		(property "Datasheet" "https://www.murata.com/products/productdetail?partno=GRM155R61H104KE14%23"
			(at 0 0 90)
			(layer "F.Fab")
			(hide yes)
			(effects
				(font
					(size 1.27 1.27)
					(thickness 0.15)
				)
			)
		)
		(property "Author" "Antmicro"
			(at 380.979998 -125.676502 0)
			(layer "F.Fab")
			(hide yes)
			(effects
				(font
					(size 1 1)
					(thickness 0.15)
				)
			)
		)
		(property "Dielectric" "X5R"
			(at 380.979998 -125.676502 0)
			(layer "F.Fab")
			(hide yes)
			(effects
				(font
					(size 1 1)
					(thickness 0.15)
				)
			)
		)
		(property "License" "Apache-2.0"
			(at 380.979998 -125.676502 0)
			(layer "F.Fab")
			(hide yes)
			(effects
				(font
					(size 1 1)
					(thickness 0.15)
				)
			)
		)
		(property "MPN" "GRM155R61H104KE14D"
			(at 380.979998 -125.676502 0)
			(layer "F.Fab")
			(hide yes)
			(effects
				(font
					(size 1 1)
					(thickness 0.15)
				)
			)
		)
		(property "Manufacturer" "Murata"
			(at 380.979998 -125.676502 0)
			(layer "F.Fab")
			(hide yes)
			(effects
				(font
					(size 1 1)
					(thickness 0.15)
				)
			)
		)
		(property "Public" "False"
			(at 380.979998 -125.676502 0)
			(layer "F.Fab")
			(hide yes)
			(effects
				(font
					(size 1 1)
					(thickness 0.15)
				)
			)
		)
		(property "Val" "100n"
			(at 380.979998 -125.676502 0)
			(layer "F.Fab")
			(hide yes)
			(effects
				(font
					(size 1 1)
					(thickness 0.15)
				)
			)
		)
		(property "Voltage" "50V"
			(at 380.979998 -125.676502 0)
			(layer "F.Fab")
			(hide yes)
			(effects
				(font
					(size 1 1)
					(thickness 0.15)
				)
			)
		)
		(sheetname "Com Express 7 MGMT")
		(sheetfile "com_express_7_mgmt.kicad_sch")
		(attr smd)
		(fp_rect
			(start -0.925 -0.47)
			(end 0.925 0.47)
			(stroke
				(width 0.05)
				(type default)
			)
			(fill no)
			(layer "F.CrtYd")
		)
		(fp_line
			(start 0.504 -0.25)
			(end 0.504 0.248)
			(stroke
				(width 0.15)
				(type solid)
			)
			(layer "F.Fab")
		)
		(fp_line
			(start -0.494 -0.25)
			(end 0.504 -0.25)
			(stroke
				(width 0.15)
				(type solid)
			)
			(layer "F.Fab")
		)
		(fp_line
			(start 0.504 0.248)
			(end -0.494 0.248)
			(stroke
				(width 0.15)
				(type solid)
			)
			(layer "F.Fab")
		)
		(fp_line
			(start -0.494 0.248)
			(end -0.494 -0.25)
			(stroke
				(width 0.15)
				(type solid)
			)
			(layer "F.Fab")
		)
		(pad "1" smd roundrect
			(at -0.48 0 90)
			(size 0.59 0.64)
			(layers "F.Cu" "F.Mask" "F.Paste")
			(roundrect_rratio 0.25)
			(net 1 "GND")
			(pintype "passive")
			(teardrops
				(best_length_ratio 0.2)
				(max_length 1)
				(best_width_ratio 0.9)
				(max_width 2)
				(curved_edges yes)
				(filter_ratio 0.9)
				(enabled yes)
				(allow_two_segments yes)
				(prefer_zone_connections yes)
			)
		)
		(pad "2" smd roundrect
			(at 0.48 0 90)
			(size 0.59 0.64)
			(layers "F.Cu" "F.Mask" "F.Paste")
			(roundrect_rratio 0.25)
			(net 73 "+3V3_AON")
			(pintype "passive")
			(teardrops
				(best_length_ratio 0.2)
				(max_length 1)
				(best_width_ratio 0.9)
				(max_width 2)
				(curved_edges yes)
				(filter_ratio 0.9)
				(enabled yes)
				(allow_two_segments yes)
				(prefer_zone_connections yes)
			)
		)
	)
	(footprint "antmicro-footprints:R_0402_1005Metric"
		(layer "F.Cu")
		(at 155.299 162.11 180)
		(descr "Resistor SMD 0402")
		(tags "resistor SMD 0402")
		(property "Reference" "R47"
			(at -6.701 17.5 0)
			(layer "F.SilkS")
			(effects
				(font
					(size 0.7 0.7)
					(thickness 0.15)
				)
				(justify right bottom)
			)
		)
		(property "Value" "R_0R_0402"
			(at -1.011843 1.772047 0)
			(layer "F.Fab")
			(effects
				(font
					(size 0.7 0.7)
					(thickness 0.15)
				)
				(justify right bottom)
			)
		)
		(property "Datasheet" "https://industrial.panasonic.com/cdbs/www-data/pdf/RDA0000/AOA0000C301.pdf"
			(at 0 0 180)
			(layer "F.Fab")
			(hide yes)
			(effects
				(font
					(size 1.27 1.27)
					(thickness 0.15)
				)
			)
		)
		(property "Author" "Antmicro"
			(at 310.598 324.22 0)
			(layer "F.Fab")
			(hide yes)
			(effects
				(font
					(size 1 1)
					(thickness 0.15)
				)
			)
		)
		(property "Current" "1A"
			(at 310.598 324.22 0)
			(layer "F.Fab")
			(hide yes)
			(effects
				(font
					(size 1 1)
					(thickness 0.15)
				)
			)
		)
		(property "License" "Apache-2.0"
			(at 310.598 324.22 0)
			(layer "F.Fab")
			(hide yes)
			(effects
				(font
					(size 1 1)
					(thickness 0.15)
				)
			)
		)
		(property "MPN" "ERJ2GE0R00X"
			(at 310.598 324.22 0)
			(layer "F.Fab")
			(hide yes)
			(effects
				(font
					(size 1 1)
					(thickness 0.15)
				)
			)
		)
		(property "Manufacturer" "Panasonic"
			(at 310.598 324.22 0)
			(layer "F.Fab")
			(hide yes)
			(effects
				(font
					(size 1 1)
					(thickness 0.15)
				)
			)
		)
		(property "Public" "False"
			(at 310.598 324.22 0)
			(layer "F.Fab")
			(hide yes)
			(effects
				(font
					(size 1 1)
					(thickness 0.15)
				)
			)
		)
		(property "Tolerance" ""
			(at 310.598 324.22 0)
			(layer "F.Fab")
			(hide yes)
			(effects
				(font
					(size 1 1)
					(thickness 0.15)
				)
			)
		)
		(property "Val" "0R"
			(at 310.598 324.22 0)
			(layer "F.Fab")
			(hide yes)
			(effects
				(font
					(size 1 1)
					(thickness 0.15)
				)
			)
		)
		(sheetname "2xSFP+")
		(sheetfile "2xSFP+.kicad_sch")
		(attr smd)
		(fp_rect
			(start -0.925 -0.47)
			(end 0.925 0.47)
			(stroke
				(width 0.05)
				(type default)
			)
			(fill no)
			(layer "F.CrtYd")
		)
		(fp_rect
			(start -0.5 -0.25)
			(end 0.5 0.25)
			(stroke
				(width 0.15)
				(type solid)
			)
			(fill no)
			(layer "F.Fab")
		)
		(pad "1" smd roundrect
			(at -0.48 0 180)
			(size 0.59 0.64)
			(layers "F.Cu" "F.Mask" "F.Paste")
			(roundrect_rratio 0.25)
			(net 566 "/2xSFP+/~{LED1_1}")
			(pintype "passive")
			(teardrops
				(best_length_ratio 0.2)
				(max_length 1)
				(best_width_ratio 0.9)
				(max_width 2)
				(curved_edges yes)
				(filter_ratio 0.9)
				(enabled yes)
				(allow_two_segments yes)
				(prefer_zone_connections yes)
			)
		)
		(pad "2" smd roundrect
			(at 0.48 0 180)
			(size 0.59 0.64)
			(layers "F.Cu" "F.Mask" "F.Paste")
			(roundrect_rratio 0.25)
			(net 929 "/2xSFP+/SFP1_LEDG")
			(pintype "passive")
			(teardrops
				(best_length_ratio 0.2)
				(max_length 1)
				(best_width_ratio 0.9)
				(max_width 2)
				(curved_edges yes)
				(filter_ratio 0.9)
				(enabled yes)
				(allow_two_segments yes)
				(prefer_zone_connections yes)
			)
		)
	)
)
